(kicad_pcb
	(version 20241229)
	(generator "pcbnew")
	(generator_version "9.0")
	(general
		(thickness 1.61)
		(legacy_teardrops no)
	)
	(paper "A3")
	(title_block
		(title "RDIMM DDR5 Tester")
		(date "2026-05-21")
		(rev "2.2.0")
		(company "Antmicro")
		(comment 9 "footprints 618-622 of 796")
	)
	(layers
		(0 "F.Cu" signal)
		(4 "In1.Cu" power)
		(6 "In2.Cu" mixed)
		(8 "In3.Cu" power)
		(10 "In4.Cu" mixed)
		(12 "In5.Cu" power)
		(14 "In6.Cu" mixed)
		(16 "In7.Cu" power)
		(18 "In8.Cu" power)
		(20 "In9.Cu" mixed)
		(22 "In10.Cu" power)
		(2 "B.Cu" signal)
		(9 "F.Adhes" user "F.Adhesive")
		(11 "B.Adhes" user "B.Adhesive")
		(13 "F.Paste" user)
		(15 "B.Paste" user)
		(5 "F.SilkS" user "F.Silkscreen")
		(7 "B.SilkS" user "B.Silkscreen")
		(1 "F.Mask" user)
		(3 "B.Mask" user)
		(17 "Dwgs.User" user "User.Drawings")
		(19 "Cmts.User" user "User.Comments")
		(21 "Eco1.User" user "User.Eco1")
		(23 "Eco2.User" user "User.Eco2")
		(25 "Edge.Cuts" user)
		(27 "Margin" user)
		(31 "F.CrtYd" user "F.Courtyard")
		(29 "B.CrtYd" user "B.Courtyard")
		(35 "F.Fab" user)
		(33 "B.Fab" user)
	)
	(footprint "antmicro-footprints:R_0402_1005Metric"
		(layer "B.Cu")
		(at 133.64 174.35 -90)
		(descr "Resistor SMD 0402")
		(tags "resistor SMD 0402")
		(property "Reference" "R239"
			(at -3.8 -0.47 90)
			(layer "B.SilkS")
			(effects
				(font
					(size 0.7 0.7)
					(thickness 0.15)
				)
				(justify left bottom mirror)
			)
		)
		(property "Value" "R_2k2_0402"
			(at -1.011843 -1.772047 90)
			(layer "B.Fab")
			(effects
				(font
					(size 0.7 0.7)
					(thickness 0.15)
				)
				(justify left bottom mirror)
			)
		)
		(property "Datasheet" "https://www.bourns.com/docs/product-datasheets/cr.pdf"
			(at 0 0 270)
			(layer "F.Fab")
			(hide yes)
			(effects
				(font
					(size 1.27 1.27)
					(thickness 0.15)
				)
			)
		)
		(property "MPN" "CR0402-FX-2201GLF"
			(at 0 0 270)
			(unlocked yes)
			(layer "B.Fab")
			(hide yes)
			(effects
				(font
					(size 1 1)
					(thickness 0.15)
				)
				(justify mirror)
			)
		)
		(property "Manufacturer" "Bourns"
			(at 0 0 270)
			(unlocked yes)
			(layer "B.Fab")
			(hide yes)
			(effects
				(font
					(size 1 1)
					(thickness 0.15)
				)
				(justify mirror)
			)
		)
		(property "License" "Apache-2.0"
			(at 0 0 270)
			(unlocked yes)
			(layer "B.Fab")
			(hide yes)
			(effects
				(font
					(size 1 1)
					(thickness 0.15)
				)
				(justify mirror)
			)
		)
		(property "Author" "Antmicro"
			(at 0 0 270)
			(unlocked yes)
			(layer "B.Fab")
			(hide yes)
			(effects
				(font
					(size 1 1)
					(thickness 0.15)
				)
				(justify mirror)
			)
		)
		(property "Val" "2k2"
			(at 0 0 270)
			(unlocked yes)
			(layer "B.Fab")
			(hide yes)
			(effects
				(font
					(size 1 1)
					(thickness 0.15)
				)
				(justify mirror)
			)
		)
		(property "Tolerance" "1%"
			(at 0 0 270)
			(unlocked yes)
			(layer "B.Fab")
			(hide yes)
			(effects
				(font
					(size 1 1)
					(thickness 0.15)
				)
				(justify mirror)
			)
		)
		(property "Public" ""
			(at 0 0 270)
			(unlocked yes)
			(layer "B.Fab")
			(hide yes)
			(effects
				(font
					(size 1 1)
					(thickness 0.15)
				)
				(justify mirror)
			)
		)
		(sheetname "/HDMI + SD Card/")
		(sheetfile "hdmi-sd-card.kicad_sch")
		(attr smd)
		(fp_rect
			(start -0.925 0.47)
			(end 0.925 -0.47)
			(stroke
				(width 0.05)
				(type default)
			)
			(fill no)
			(layer "B.CrtYd")
		)
		(fp_rect
			(start -0.5 0.25)
			(end 0.5 -0.25)
			(stroke
				(width 0.15)
				(type solid)
			)
			(fill no)
			(layer "B.Fab")
		)
		(fp_text user "${REFERENCE}"
			(at -0.95 -3.168 90)
			(layer "B.Fab")
			(effects
				(font
					(size 0.7 0.7)
					(thickness 0.15)
				)
				(justify left bottom mirror)
			)
		)
		(fp_text user "Author: Antmicro"
			(at -0.95 -4.169 90)
			(layer "B.Fab")
			(effects
				(font
					(size 0.7 0.7)
					(thickness 0.15)
				)
				(justify left bottom mirror)
			)
		)
		(fp_text user "License: Apache-2.0"
			(at -0.95 -5.169 90)
			(layer "B.Fab")
			(effects
				(font
					(size 0.7 0.7)
					(thickness 0.15)
				)
				(justify left bottom mirror)
			)
		)
		(pad "1" smd roundrect
			(at -0.48 0 270)
			(size 0.59 0.64)
			(layers "B.Cu" "B.Mask" "B.Paste")
			(roundrect_rratio 0.25)
			(net 768 "/FPGA MGT Interface/HDMI_CTL.SCL")
			(pintype "passive")
		)
		(pad "2" smd roundrect
			(at 0.48 0 270)
			(size 0.59 0.64)
			(layers "B.Cu" "B.Mask" "B.Paste")
			(roundrect_rratio 0.25)
			(net 151 "+3V3")
			(pintype "passive")
		)
	)
	(footprint "antmicro-footprints:C_0402_1005Metric_EIA"
		(layer "B.Cu")
		(at 187 148.499999 -90)
		(descr "Capacitor SMD 0402 (1005 Metric), square (rectangular) end terminal, IPC_7351 nominal, (Body size source: IPC-SM-782 page 76, https://www.pcb-3d.com/wordpress/wp-content/uploads/ipc-sm-782a_amendment_1_and_2.pdf)")
		(tags "capacitor 0402")
		(property "Reference" "C40"
			(at -11.699999 30.625 90)
			(layer "B.SilkS")
			(effects
				(font
					(size 0.7 0.7)
					(thickness 0.15)
				)
				(justify left bottom mirror)
			)
		)
		(property "Value" "C_1u_25V_0402"
			(at 0 -1.169 90)
			(layer "B.Fab")
			(effects
				(font
					(size 0.7 0.7)
					(thickness 0.15)
				)
				(justify left bottom mirror)
			)
		)
		(property "Datasheet" "https://www.murata.com/products/productdetail?partno=GRM155R61E105KE11%23"
			(at 0 0 270)
			(layer "F.Fab")
			(hide yes)
			(effects
				(font
					(size 1.27 1.27)
					(thickness 0.15)
				)
			)
		)
		(property "MPN" "GRM155R61E105KE11J"
			(at 0 0 270)
			(unlocked yes)
			(layer "B.Fab")
			(hide yes)
			(effects
				(font
					(size 1 1)
					(thickness 0.15)
				)
				(justify mirror)
			)
		)
		(property "Manufacturer" "Murata"
			(at 0 0 270)
			(unlocked yes)
			(layer "B.Fab")
			(hide yes)
			(effects
				(font
					(size 1 1)
					(thickness 0.15)
				)
				(justify mirror)
			)
		)
		(property "License" "Apache-2.0"
			(at 0 0 270)
			(unlocked yes)
			(layer "B.Fab")
			(hide yes)
			(effects
				(font
					(size 1 1)
					(thickness 0.15)
				)
				(justify mirror)
			)
		)
		(property "Author" "Antmicro"
			(at 0 0 270)
			(unlocked yes)
			(layer "B.Fab")
			(hide yes)
			(effects
				(font
					(size 1 1)
					(thickness 0.15)
				)
				(justify mirror)
			)
		)
		(property "Val" "1u"
			(at 0 0 270)
			(unlocked yes)
			(layer "B.Fab")
			(hide yes)
			(effects
				(font
					(size 1 1)
					(thickness 0.15)
				)
				(justify mirror)
			)
		)
		(property "Voltage" "25V"
			(at 0 0 270)
			(unlocked yes)
			(layer "B.Fab")
			(hide yes)
			(effects
				(font
					(size 1 1)
					(thickness 0.15)
				)
				(justify mirror)
			)
		)
		(property "Dielectric" "X5R"
			(at 0 0 270)
			(unlocked yes)
			(layer "B.Fab")
			(hide yes)
			(effects
				(font
					(size 1 1)
					(thickness 0.15)
				)
				(justify mirror)
			)
		)
		(sheetname "/FPGA power/")
		(sheetfile "fpga-power.kicad_sch")
		(attr smd)
		(fp_rect
			(start -0.95 0.45)
			(end 0.95 -0.45)
			(stroke
				(width 0.05)
				(type default)
			)
			(fill no)
			(layer "B.CrtYd")
		)
		(fp_line
			(start -0.5 0.25)
			(end 0.498 0.25)
			(stroke
				(width 0.15)
				(type solid)
			)
			(layer "B.Fab")
		)
		(fp_line
			(start 0.498 0.25)
			(end 0.498 -0.248)
			(stroke
				(width 0.15)
				(type solid)
			)
			(layer "B.Fab")
		)
		(fp_line
			(start -0.5 -0.248)
			(end -0.5 0.25)
			(stroke
				(width 0.15)
				(type solid)
			)
			(layer "B.Fab")
		)
		(fp_line
			(start 0.498 -0.248)
			(end -0.5 -0.248)
			(stroke
				(width 0.15)
				(type solid)
			)
			(layer "B.Fab")
		)
		(fp_text user "License: Apache-2.0"
			(at -0.9656 -4.369 90)
			(layer "B.Fab")
			(effects
				(font
					(size 0.7 0.7)
					(thickness 0.15)
				)
				(justify left bottom mirror)
			)
		)
		(fp_text user "Author: Antmicro"
			(at -0.9656 -5.569 90)
			(layer "B.Fab")
			(effects
				(font
					(size 0.7 0.7)
					(thickness 0.15)
				)
				(justify left bottom mirror)
			)
		)
		(fp_text user "${REFERENCE}"
			(at -0.9656 -3.169 90)
			(layer "B.Fab")
			(effects
				(font
					(size 0.7 0.7)
					(thickness 0.15)
				)
				(justify left bottom mirror)
			)
		)
		(pad "1" smd roundrect
			(at -0.5 0 180)
			(size 0.6 0.6)
			(layers "B.Cu" "B.Mask" "B.Paste")
			(roundrect_rratio 0.25)
			(net 1 "GND")
			(pintype "passive")
		)
		(pad "2" smd roundrect
			(at 0.498 0 270)
			(size 0.6 0.6)
			(layers "B.Cu" "B.Mask" "B.Paste")
			(roundrect_rratio 0.25)
			(net 553 "+0V85")
			(pintype "passive")
		)
	)
	(footprint "antmicro-footprints:C_0402_1005Metric"
		(layer "B.Cu")
		(at 124.2 164.05 180)
		(descr "Capacitor SMD 0402")
		(tags "capacitor SMD 0402")
		(property "Reference" "C296"
			(at -4.05 -0.35 0)
			(layer "B.SilkS")
			(effects
				(font
					(size 0.7 0.7)
					(thickness 0.15)
				)
				(justify left bottom mirror)
			)
		)
		(property "Value" "C_100n_0402"
			(at -1.022927 -2.155213 0)
			(layer "B.Fab")
			(effects
				(font
					(size 0.7 0.7)
					(thickness 0.15)
				)
				(justify left bottom mirror)
			)
		)
		(property "Datasheet" "https://www.murata.com/products/productdetail?partno=GRM155R61H104KE14%23"
			(at 0 0 180)
			(layer "F.Fab")
			(hide yes)
			(effects
				(font
					(size 1.27 1.27)
					(thickness 0.15)
				)
			)
		)
		(property "MPN" "GRM155R61H104KE14D"
			(at 0 0 180)
			(unlocked yes)
			(layer "B.Fab")
			(hide yes)
			(effects
				(font
					(size 1 1)
					(thickness 0.15)
				)
				(justify mirror)
			)
		)
		(property "Manufacturer" "Murata"
			(at 0 0 180)
			(unlocked yes)
			(layer "B.Fab")
			(hide yes)
			(effects
				(font
					(size 1 1)
					(thickness 0.15)
				)
				(justify mirror)
			)
		)
		(property "License" "Apache-2.0"
			(at 0 0 180)
			(unlocked yes)
			(layer "B.Fab")
			(hide yes)
			(effects
				(font
					(size 1 1)
					(thickness 0.15)
				)
				(justify mirror)
			)
		)
		(property "Author" "Antmicro"
			(at 0 0 180)
			(unlocked yes)
			(layer "B.Fab")
			(hide yes)
			(effects
				(font
					(size 1 1)
					(thickness 0.15)
				)
				(justify mirror)
			)
		)
		(property "Val" "100n"
			(at 0 0 180)
			(unlocked yes)
			(layer "B.Fab")
			(hide yes)
			(effects
				(font
					(size 1 1)
					(thickness 0.15)
				)
				(justify mirror)
			)
		)
		(property "Voltage" "50V"
			(at 0 0 180)
			(unlocked yes)
			(layer "B.Fab")
			(hide yes)
			(effects
				(font
					(size 1 1)
					(thickness 0.15)
				)
				(justify mirror)
			)
		)
		(property "Dielectric" "X5R"
			(at 0 0 180)
			(unlocked yes)
			(layer "B.Fab")
			(hide yes)
			(effects
				(font
					(size 1 1)
					(thickness 0.15)
				)
				(justify mirror)
			)
		)
		(sheetname "/HDMI + SD Card/")
		(sheetfile "hdmi-sd-card.kicad_sch")
		(attr smd)
		(fp_rect
			(start -0.925 0.47)
			(end 0.925 -0.47)
			(stroke
				(width 0.05)
				(type default)
			)
			(fill no)
			(layer "B.CrtYd")
		)
		(fp_line
			(start 0.504 0.25)
			(end 0.504 -0.248)
			(stroke
				(width 0.15)
				(type solid)
			)
			(layer "B.Fab")
		)
		(fp_line
			(start 0.504 -0.248)
			(end -0.494 -0.248)
			(stroke
				(width 0.15)
				(type solid)
			)
			(layer "B.Fab")
		)
		(fp_line
			(start -0.494 0.25)
			(end 0.504 0.25)
			(stroke
				(width 0.15)
				(type solid)
			)
			(layer "B.Fab")
		)
		(fp_line
			(start -0.494 -0.248)
			(end -0.494 0.25)
			(stroke
				(width 0.15)
				(type solid)
			)
			(layer "B.Fab")
		)
		(fp_text user "${REFERENCE}"
			(at -0.939 -4.599 0)
			(layer "B.Fab")
			(effects
				(font
					(size 0.7 0.7)
					(thickness 0.15)
				)
				(justify left bottom mirror)
			)
		)
		(fp_text user "Author: Antmicro"
			(at -0.939 -3.399 0)
			(layer "B.Fab")
			(effects
				(font
					(size 0.7 0.7)
					(thickness 0.15)
				)
				(justify left bottom mirror)
			)
		)
		(fp_text user "License: Apache-2.0"
			(at -0.939 -5.799 0)
			(layer "B.Fab")
			(effects
				(font
					(size 0.7 0.7)
					(thickness 0.15)
				)
				(justify left bottom mirror)
			)
		)
		(pad "1" smd roundrect
			(at -0.48 0 180)
			(size 0.59 0.64)
			(layers "B.Cu" "B.Mask" "B.Paste")
			(roundrect_rratio 0.25)
			(net 1 "GND")
			(pintype "passive")
		)
		(pad "2" smd roundrect
			(at 0.48 0 180)
			(size 0.59 0.64)
			(layers "B.Cu" "B.Mask" "B.Paste")
			(roundrect_rratio 0.25)
			(net 797 "+1V8")
			(pintype "passive")
		)
	)
	(footprint "antmicro-footprints:C_0402_1005Metric_EIA"
		(layer "B.Cu")
		(at 184.498 157)
		(descr "Capacitor SMD 0402 (1005 Metric), square (rectangular) end terminal, IPC_7351 nominal, (Body size source: IPC-SM-782 page 76, https://www.pcb-3d.com/wordpress/wp-content/uploads/ipc-sm-782a_amendment_1_and_2.pdf)")
		(tags "capacitor 0402")
		(property "Reference" "C53"
			(at -32.248 -10.525 0)
			(layer "B.SilkS")
			(effects
				(font
					(size 0.7 0.7)
					(thickness 0.15)
				)
				(justify right bottom mirror)
			)
		)
		(property "Value" "C_1u_25V_0402"
			(at 0 -1.169 0)
			(layer "B.Fab")
			(effects
				(font
					(size 0.7 0.7)
					(thickness 0.15)
				)
				(justify right bottom mirror)
			)
		)
		(property "Datasheet" "https://www.murata.com/products/productdetail?partno=GRM155R61E105KE11%23"
			(at 0 0 0)
			(layer "F.Fab")
			(hide yes)
			(effects
				(font
					(size 1.27 1.27)
					(thickness 0.15)
				)
			)
		)
		(property "MPN" "GRM155R61E105KE11J"
			(at 0 0 0)
			(unlocked yes)
			(layer "B.Fab")
			(hide yes)
			(effects
				(font
					(size 1 1)
					(thickness 0.15)
				)
				(justify mirror)
			)
		)
		(property "Manufacturer" "Murata"
			(at 0 0 0)
			(unlocked yes)
			(layer "B.Fab")
			(hide yes)
			(effects
				(font
					(size 1 1)
					(thickness 0.15)
				)
				(justify mirror)
			)
		)
		(property "License" "Apache-2.0"
			(at 0 0 0)
			(unlocked yes)
			(layer "B.Fab")
			(hide yes)
			(effects
				(font
					(size 1 1)
					(thickness 0.15)
				)
				(justify mirror)
			)
		)
		(property "Author" "Antmicro"
			(at 0 0 0)
			(unlocked yes)
			(layer "B.Fab")
			(hide yes)
			(effects
				(font
					(size 1 1)
					(thickness 0.15)
				)
				(justify mirror)
			)
		)
		(property "Val" "1u"
			(at 0 0 0)
			(unlocked yes)
			(layer "B.Fab")
			(hide yes)
			(effects
				(font
					(size 1 1)
					(thickness 0.15)
				)
				(justify mirror)
			)
		)
		(property "Voltage" "25V"
			(at 0 0 0)
			(unlocked yes)
			(layer "B.Fab")
			(hide yes)
			(effects
				(font
					(size 1 1)
					(thickness 0.15)
				)
				(justify mirror)
			)
		)
		(property "Dielectric" "X5R"
			(at 0 0 0)
			(unlocked yes)
			(layer "B.Fab")
			(hide yes)
			(effects
				(font
					(size 1 1)
					(thickness 0.15)
				)
				(justify mirror)
			)
		)
		(sheetname "/FPGA power/")
		(sheetfile "fpga-power.kicad_sch")
		(attr smd)
		(fp_rect
			(start -0.95 0.45)
			(end 0.95 -0.45)
			(stroke
				(width 0.05)
				(type default)
			)
			(fill no)
			(layer "B.CrtYd")
		)
		(fp_line
			(start -0.5 -0.248)
			(end -0.5 0.25)
			(stroke
				(width 0.15)
				(type solid)
			)
			(layer "B.Fab")
		)
		(fp_line
			(start -0.5 0.25)
			(end 0.498 0.25)
			(stroke
				(width 0.15)
				(type solid)
			)
			(layer "B.Fab")
		)
		(fp_line
			(start 0.498 -0.248)
			(end -0.5 -0.248)
			(stroke
				(width 0.15)
				(type solid)
			)
			(layer "B.Fab")
		)
		(fp_line
			(start 0.498 0.25)
			(end 0.498 -0.248)
			(stroke
				(width 0.15)
				(type solid)
			)
			(layer "B.Fab")
		)
		(fp_text user "License: Apache-2.0"
			(at -0.9656 -4.369 180)
			(layer "B.Fab")
			(effects
				(font
					(size 0.7 0.7)
					(thickness 0.15)
				)
				(justify left bottom mirror)
			)
		)
		(fp_text user "${REFERENCE}"
			(at -0.9656 -3.169 180)
			(layer "B.Fab")
			(effects
				(font
					(size 0.7 0.7)
					(thickness 0.15)
				)
				(justify left bottom mirror)
			)
		)
		(fp_text user "Author: Antmicro"
			(at -0.9656 -5.569 180)
			(layer "B.Fab")
			(effects
				(font
					(size 0.7 0.7)
					(thickness 0.15)
				)
				(justify left bottom mirror)
			)
		)
		(pad "1" smd roundrect
			(at -0.5 0 270)
			(size 0.6 0.6)
			(layers "B.Cu" "B.Mask" "B.Paste")
			(roundrect_rratio 0.25)
			(net 1 "GND")
			(pintype "passive")
		)
		(pad "2" smd roundrect
			(at 0.498 0)
			(size 0.6 0.6)
			(layers "B.Cu" "B.Mask" "B.Paste")
			(roundrect_rratio 0.25)
			(net 553 "+0V85")
			(pintype "passive")
		)
	)
	(footprint "antmicro-footprints:C_0402_1005Metric"
		(layer "B.Cu")
		(at 159.624499 193.228 -90)
		(descr "Capacitor SMD 0402")
		(tags "capacitor SMD 0402")
		(property "Reference" "C258"
			(at -3.774 -0.435501 90)
			(layer "B.SilkS")
			(effects
				(font
					(size 0.7 0.7)
					(thickness 0.15)
				)
				(justify left bottom mirror)
			)
		)
		(property "Value" "C_10n_0402"
			(at -1.022927 -2.155213 90)
			(layer "B.Fab")
			(effects
				(font
					(size 0.7 0.7)
					(thickness 0.15)
				)
				(justify left bottom mirror)
			)
		)
		(property "Datasheet" "https://www.murata.com/products/productdetail?partno=GRM155R71H103KA88%23"
			(at 0 0 270)
			(layer "F.Fab")
			(hide yes)
			(effects
				(font
					(size 1.27 1.27)
					(thickness 0.15)
				)
			)
		)
		(property "MPN" "GRM155R71H103KA88D"
			(at 0 0 270)
			(unlocked yes)
			(layer "B.Fab")
			(hide yes)
			(effects
				(font
					(size 1 1)
					(thickness 0.15)
				)
				(justify mirror)
			)
		)
		(property "Manufacturer" "Murata"
			(at 0 0 270)
			(unlocked yes)
			(layer "B.Fab")
			(hide yes)
			(effects
				(font
					(size 1 1)
					(thickness 0.15)
				)
				(justify mirror)
			)
		)
		(property "License" "Apache-2.0"
			(at 0 0 270)
			(unlocked yes)
			(layer "B.Fab")
			(hide yes)
			(effects
				(font
					(size 1 1)
					(thickness 0.15)
				)
				(justify mirror)
			)
		)
		(property "Author" "Antmicro"
			(at 0 0 270)
			(unlocked yes)
			(layer "B.Fab")
			(hide yes)
			(effects
				(font
					(size 1 1)
					(thickness 0.15)
				)
				(justify mirror)
			)
		)
		(property "Val" "10n"
			(at 0 0 270)
			(unlocked yes)
			(layer "B.Fab")
			(hide yes)
			(effects
				(font
					(size 1 1)
					(thickness 0.15)
				)
				(justify mirror)
			)
		)
		(property "Voltage" "50V"
			(at 0 0 270)
			(unlocked yes)
			(layer "B.Fab")
			(hide yes)
			(effects
				(font
					(size 1 1)
					(thickness 0.15)
				)
				(justify mirror)
			)
		)
		(property "Dielectric" "X7R"
			(at 0 0 270)
			(unlocked yes)
			(layer "B.Fab")
			(hide yes)
			(effects
				(font
					(size 1 1)
					(thickness 0.15)
				)
				(justify mirror)
			)
		)
		(sheetname "/FPGA MGT Interface/")
		(sheetfile "fpga-mgt.kicad_sch")
		(attr smd)
		(fp_rect
			(start -0.925 0.47)
			(end 0.925 -0.47)
			(stroke
				(width 0.05)
				(type default)
			)
			(fill no)
			(layer "B.CrtYd")
		)
		(fp_line
			(start -0.494 0.25)
			(end 0.504 0.25)
			(stroke
				(width 0.15)
				(type solid)
			)
			(layer "B.Fab")
		)
		(fp_line
			(start 0.504 0.25)
			(end 0.504 -0.248)
			(stroke
				(width 0.15)
				(type solid)
			)
			(layer "B.Fab")
		)
		(fp_line
			(start -0.494 -0.248)
			(end -0.494 0.25)
			(stroke
				(width 0.15)
				(type solid)
			)
			(layer "B.Fab")
		)
		(fp_line
			(start 0.504 -0.248)
			(end -0.494 -0.248)
			(stroke
				(width 0.15)
				(type solid)
			)
			(layer "B.Fab")
		)
		(fp_text user "License: Apache-2.0"
			(at -0.939 -5.799 90)
			(layer "B.Fab")
			(effects
				(font
					(size 0.7 0.7)
					(thickness 0.15)
				)
				(justify left bottom mirror)
			)
		)
		(fp_text user "${REFERENCE}"
			(at -0.939 -4.599 90)
			(layer "B.Fab")
			(effects
				(font
					(size 0.7 0.7)
					(thickness 0.15)
				)
				(justify left bottom mirror)
			)
		)
		(fp_text user "Author: Antmicro"
			(at -0.939 -3.399 90)
			(layer "B.Fab")
			(effects
				(font
					(size 0.7 0.7)
					(thickness 0.15)
				)
				(justify left bottom mirror)
			)
		)
		(pad "1" smd roundrect
			(at -0.48 0 270)
			(size 0.59 0.64)
			(layers "B.Cu" "B.Mask" "B.Paste")
			(roundrect_rratio 0.25)
			(net 12 "/FPGA MGT Interface/GTR_REFCLK0_P")
			(pintype "passive")
		)
		(pad "2" smd roundrect
			(at 0.48 0 270)
			(size 0.59 0.64)
			(layers "B.Cu" "B.Mask" "B.Paste")
			(roundrect_rratio 0.25)
			(net 11 "/FPGA MGT Interface/PCIE.CLK_P")
			(pintype "passive")
		)
	)
)
